# BASEBOARD_FAB2 (Tioga Pass) — schematic netlist excerpt (pin names and nets, part order shuffled) for the footprints in the layout excerpt that follows; sources: Cadence DE-HDL packaged netlist, KiCad conversion of Wiwynn_Tioga_Pass_MB.brd

EU8F2  ICS9FGP204  IC  pkg MLFP  page 101
  GND(0)  = GND
  VDD96  = P3V3_STBY_MNG
  DOT96SST  = TP_CLK_96M_CKMNG_P
  DOT96SSC  = TP_CLK_96M_CKMNG_N
  OE_96  = PD_CKMNG_OE
  OE_CPU  = PD_CKMNG_OE
  CPUCLKT0  = TP_CLK_100M_R_DP
  CPUCLKC0  = TP_CLK_100M_R_DN
  VDDCPU  = P3V3_STBY_MNG_CPU
  GNDCPU  = GND
  IREF  = A_COMP_CKMNG
  VDD32K  = P3V3_STBY_MNG
  \32khz\  = CLK_32K_SUSCLK_PLD_R
  GND32K  = GND
  VDDREF  = P3V3_STBY_MNG
  \25mhz_0\  = CLK_25M_BMC_R
  \25mhz_1\  = CLK_25M_CPLD_R
  GNDREF  = GND
  X1_25  = XTAL_CK_MNG_IN
  X2_25  = XTAL_CK_MNG_OUT_R
  GND33  = GND
  \33mhz_smbadr\  = PU_33P_33M_SMBADR
  VDD33  = P3V3_STBY_MNG
  RMII(5)  = TP_CLK5_50M_CKMNG
  RMII(4)  = CLK_50M_CKMNG_PCH_10GBE_R
  VDDRMII(0)  = P3V3_STBY_MNG_RMII
  GNDRMII(0)  = GND
  RMII(3)  = CLK_50M_CKMNG_SPRVLLE_R
  RMII(2)  = CLK_50M_CKMNG_BMC_2_R
  GNDRMII(1)  = GND
  VDDRMII(1)  = P3V3_STBY_MNG_RMII
  RMII(1)  = CLK_50M_CKMNG_BMC_1_R
  RMII(0)  = CLK_50M_CKMNG_OCP_R
  VDD_RGMII  = P3V3_STBY_MNG_RGMII
  GND_RGMII  = GND
  RGMII(1)  = TP_CLK_125M
  RGMII(0)  = TP_CLK_125M_BMCA
  SMBCLK  = SMB_HOST_STBY_LVC3_SCL_R4
  SMBDAT  = SMB_HOST_STBY_LVC3_SDA_R4
  VTTPWR_GD_PD_N  = PWRGD_P3V3_STBY
  GND(1)  = GND

(kicad_pcb
	(version 20260206)
	(generator "pcbnew")
	(generator_version "10.0")
	(general
		(thickness 1.6)
		(legacy_teardrops no)
	)
	(paper "A4")
	(title_block
		(title "Wiwynn_Tioga_Pass_MB.brd")
		(comment 1 "Tioga Pass / footprint 997 of 4770 (EU8F2), pads 35-41 of 41")
	)
	(layers
		(0 "F.Cu" signal "TOP")
		(4 "In1.Cu" signal "L2GND")
		(6 "In2.Cu" signal "L3")
		(8 "In3.Cu" signal "L4GND")
		(10 "In4.Cu" signal "L5")
		(12 "In5.Cu" signal "L6GND")
		(14 "In6.Cu" signal "L7VCC")
		(16 "In7.Cu" signal "L8VCC")
		(18 "In8.Cu" signal "L9GND")
		(20 "In9.Cu" signal "L10")
		(22 "In10.Cu" signal "L11GND")
		(24 "In11.Cu" signal "L12")
		(26 "In12.Cu" signal "L13GND")
		(2 "B.Cu" signal "BOTTOM")
		(9 "F.Adhes" user "F.Adhesive")
		(11 "B.Adhes" user "B.Adhesive")
		(13 "F.Paste" user "Package Geometry/Pastemask Top")
		(15 "B.Paste" user "Package Geometry/Pastemask Bottom")
		(5 "F.SilkS" user "Ref Des/Silkscreen Top")
		(7 "B.SilkS" user "Ref Des/Silkscreen Bottom")
		(1 "F.Mask" user "Board Geometry/Soldermask Top")
		(3 "B.Mask" user "Board Geometry/Soldermask Bottom")
		(17 "Dwgs.User" user "User.Drawings")
		(19 "Cmts.User" user "User.Comments")
		(21 "Eco1.User" user "User.Eco1")
		(23 "Eco2.User" user "User.Eco2")
		(25 "Edge.Cuts" user "Board Geometry/Outline")
		(27 "Margin" user)
		(31 "F.CrtYd" user "Package Geometry/Place Bound Top")
		(29 "B.CrtYd" user "Package Geometry/Place Bound Bottom")
		(35 "F.Fab" user "Ref Des/Assembly Top")
		(33 "B.Fab" user "Ref Des/Assembly Bottom")
	)
	(footprint ""
		(layer "F.Cu")
		(at 475.64802 -27.7495 90)
		(property "Reference" "EU8F2"
			(at 8.88365 7.29996 180)
			(unlocked yes)
			(layer "F.SilkS")
			(effects
				(font
					(size 0.7874 0.5842)
					(thickness 0.1524)
				)
			)
		)
		(property "Value" ""
			(at 0 0 90)
			(layer "F.Fab")
			(effects
				(font
					(size 1.27 1.27)
				)
			)
		)
		(duplicate_pad_numbers_are_jumpers no)
		(pad "35" smd custom
			(at 3.36042 -0.85852 90)
			(size 0.0762 0.0762)
			(layers "F.Cu" "F.Mask" "F.Paste")
			(net "GND")
			(options
				(clearance outline)
				(anchor circle)
			)
			(primitives
				(gr_poly
					(pts
						(xy 0.1524 -0.5715)
						(arc
							(start 0.1524 0.4191)
							(mid 0 0.5715)
							(end -0.1524 0.4191)
						)
						(xy -0.1524 -0.5715)
					)
					(width 0)
					(fill yes)
				)
			)
		)
		(pad "36" smd custom
			(at 2.86004 -0.85852 90)
			(size 0.0762 0.0762)
			(layers "F.Cu" "F.Mask" "F.Paste")
			(net "TP_CLK_125M")
			(options
				(clearance outline)
				(anchor circle)
			)
			(primitives
				(gr_poly
					(pts
						(xy 0.1524 -0.5715)
						(arc
							(start 0.1524 0.4191)
							(mid 0 0.5715)
							(end -0.1524 0.4191)
						)
						(xy -0.1524 -0.5715)
					)
					(width 0)
					(fill yes)
				)
			)
		)
		(pad "37" smd custom
			(at 2.35966 -0.85852 90)
			(size 0.0762 0.0762)
			(layers "F.Cu" "F.Mask" "F.Paste")
			(net "TP_CLK_125M_BMCA")
			(options
				(clearance outline)
				(anchor circle)
			)
			(primitives
				(gr_poly
					(pts
						(xy 0.1524 -0.5715)
						(arc
							(start 0.1524 0.4191)
							(mid 0 0.5715)
							(end -0.1524 0.4191)
						)
						(xy -0.1524 -0.5715)
					)
					(width 0)
					(fill yes)
				)
			)
		)
		(pad "38" smd custom
			(at 1.85928 -0.85852 90)
			(size 0.0762 0.0762)
			(layers "F.Cu" "F.Mask" "F.Paste")
			(net "SMB_HOST_STBY_LVC3_SCL_R4")
			(options
				(clearance outline)
				(anchor circle)
			)
			(primitives
				(gr_poly
					(pts
						(xy 0.1524 -0.5715)
						(arc
							(start 0.1524 0.4191)
							(mid 0 0.5715)
							(end -0.1524 0.4191)
						)
						(xy -0.1524 -0.5715)
					)
					(width 0)
					(fill yes)
				)
			)
		)
		(pad "39" smd custom
			(at 1.3589 -0.85852 90)
			(size 0.0762 0.0762)
			(layers "F.Cu" "F.Mask" "F.Paste")
			(net "SMB_HOST_STBY_LVC3_SDA_R4")
			(options
				(clearance outline)
				(anchor circle)
			)
			(primitives
				(gr_poly
					(pts
						(xy 0.1524 -0.5715)
						(arc
							(start 0.1524 0.4191)
							(mid 0 0.5715)
							(end -0.1524 0.4191)
						)
						(xy -0.1524 -0.5715)
					)
					(width 0)
					(fill yes)
				)
			)
		)
		(pad "40" smd custom
			(at 0.85852 -0.85852 90)
			(size 0.0762 0.0762)
			(layers "F.Cu" "F.Mask" "F.Paste")
			(net "PWRGD_P3V3_STBY")
			(options
				(clearance outline)
				(anchor circle)
			)
			(primitives
				(gr_poly
					(pts
						(xy 0.1524 -0.5715)
						(arc
							(start 0.1524 0.4191)
							(mid 0 0.5715)
							(end -0.1524 0.4191)
						)
						(xy -0.1524 -0.5715)
					)
					(width 0)
					(fill yes)
				)
			)
		)
		(pad "41" smd rect
			(at 3.1115 2.25298 90)
			(size 4.0894 4.0894)
			(layers "F.Cu" "F.Mask" "F.Paste")
			(net "GND")
		)
	)
)
